# S9S_MB_2U (Grand Teton) — schematic netlist excerpt (pin names and nets, part order shuffled) for the footprints in the layout excerpt that follows; sources: Cadence DE-HDL packaged netlist, KiCad conversion of 03242023_DA0F0TMBIJ0_F0T_Motherboard_J_brd_V01_OCP.brd

C1569  Q_CAP_DIFFBUS  DIFF BUS_0.22UF 6.3V 20% X6S  pkg C0201  page 175 : \1\ = P5E_CPU0_PE4_TX_C_DP<5> ; \2\ = P5E_CPU0_PE4_TX_DP<5>

J72  PICOPROBE_BXA  DELTA-L 4.0 EMPTY  pkg TRIANG_LAUNCH_3PXB  page 308
  \1_p\  = DELTA_L_85_5INCH_IN2_DN
  \2_n\  = DELTA_L_85_5INCH_IN2_DP
  \3_g\  = DELTA_L_GND_1

(kicad_pcb
	(version 20260206)
	(generator "pcbnew")
	(generator_version "10.0")
	(general
		(thickness 1.6)
		(legacy_teardrops no)
	)
	(paper "A4")
	(title_block
		(title "03242023_DA0F0TMBIJ0_F0T_Motherboard_J_brd_V01_OCP.brd")
		(comment 1 "Grand Teton / footprints 1361-1362 of 6105")
	)
	(layers
		(0 "F.Cu" signal "TOP")
		(4 "In1.Cu" signal "GND")
		(6 "In2.Cu" signal "IN1")
		(8 "In3.Cu" signal "GND1")
		(10 "In4.Cu" signal "IN2")
		(12 "In5.Cu" signal "GND2")
		(14 "In6.Cu" signal "IN3")
		(16 "In7.Cu" signal "GND3")
		(18 "In8.Cu" signal "VCC")
		(20 "In9.Cu" signal "VCC1")
		(22 "In10.Cu" signal "GND4")
		(24 "In11.Cu" signal "IN4")
		(26 "In12.Cu" signal "GND5")
		(28 "In13.Cu" signal "IN5")
		(30 "In14.Cu" signal "GND6")
		(32 "In15.Cu" signal "IN6")
		(34 "In16.Cu" signal "GND7")
		(2 "B.Cu" signal "BOTTOM")
		(9 "F.Adhes" user "F.Adhesive")
		(11 "B.Adhes" user "B.Adhesive")
		(13 "F.Paste" user "Package Geometry/Pastemask Top")
		(15 "B.Paste" user "Package Geometry/Pastemask Bottom")
		(5 "F.SilkS" user "Ref Des/Silkscreen Top")
		(7 "B.SilkS" user "Ref Des/Silkscreen Bottom")
		(1 "F.Mask" user "Board Geometry/Soldermask Top")
		(3 "B.Mask" user "Board Geometry/Soldermask Bottom")
		(17 "Dwgs.User" user "User.Drawings")
		(19 "Cmts.User" user "User.Comments")
		(21 "Eco1.User" user "User.Eco1")
		(23 "Eco2.User" user "User.Eco2")
		(25 "Edge.Cuts" user "Board Geometry/Outline")
		(27 "Margin" user)
		(31 "F.CrtYd" user "Package Geometry/Place Bound Top")
		(29 "B.CrtYd" user "Package Geometry/Place Bound Bottom")
		(35 "F.Fab" user "Ref Des/Assembly Top")
		(33 "B.Fab" user "Ref Des/Assembly Bottom")
	)
	(footprint ""
		(layer "F.Cu")
		(at 339.298534 5.463794)
		(property "Reference" "J72"
			(at -4.245864 1.140206 90)
			(unlocked yes)
			(layer "F.SilkS")
			(effects
				(font
					(size 0.7874 0.5842)
					(thickness 0.1524)
				)
				(justify left)
			)
		)
		(property "Value" ""
			(at 0 0 0)
			(layer "F.Fab")
			(effects
				(font
					(size 1.27 1.27)
				)
			)
		)
		(duplicate_pad_numbers_are_jumpers no)
		(fp_line
			(start -1.2192 -2.1082)
			(end 1.2192 -2.1082)
			(stroke
				(width 0.1524)
				(type default)
			)
			(layer "F.SilkS")
		)
		(fp_line
			(start -1.2192 2.1082)
			(end -1.2192 -2.1082)
			(stroke
				(width 0.1524)
				(type default)
			)
			(layer "F.SilkS")
		)
		(fp_line
			(start 1.2192 -2.1082)
			(end 1.2192 2.1082)
			(stroke
				(width 0.1524)
				(type default)
			)
			(layer "F.SilkS")
		)
		(fp_line
			(start 1.2192 2.1082)
			(end -1.2192 2.1082)
			(stroke
				(width 0.1524)
				(type default)
			)
			(layer "F.SilkS")
		)
		(pad "" np_thru_hole circle
			(at -2.8829 -1.27 270)
			(size 1.0414 1.0414)
			(drill 1.0414)
			(layers "*.Cu" "*.Mask")
			(clearance 0.381)
			(thermal_gap 0.381)
		)
		(pad "" np_thru_hole circle
			(at -2.8829 1.27 270)
			(size 1.0414 1.0414)
			(drill 1.0414)
			(layers "*.Cu" "*.Mask")
			(clearance 0.381)
			(thermal_gap 0.381)
		)
		(pad "" np_thru_hole circle
			(at 3.4671 -1.27 270)
			(size 1.0414 1.0414)
			(drill 1.0414)
			(layers "*.Cu" "*.Mask")
			(clearance 0.381)
			(thermal_gap 0.381)
		)
		(pad "" np_thru_hole circle
			(at 3.4671 1.27 270)
			(size 1.0414 1.0414)
			(drill 1.0414)
			(layers "*.Cu" "*.Mask")
			(clearance 0.381)
			(thermal_gap 0.381)
		)
		(pad "1" smd rect
			(at 0.8255 -0.249936 270)
			(size 0.3048 0.508)
			(layers "F.Cu" "F.Mask" "F.Paste")
			(net "DELTA_L_85_5INCH_IN2_DN")
		)
		(pad "2" smd rect
			(at 0.8255 0.249936 270)
			(size 0.3048 0.508)
			(layers "F.Cu" "F.Mask" "F.Paste")
			(net "DELTA_L_85_5INCH_IN2_DP")
		)
		(pad "3" smd circle
			(at 0 0)
			(size 0 0)
			(layers "F.Cu" "F.Mask" "F.Paste")
			(net "DELTA_L_GND_1")
		)
		(zone
			(layer "F.Cu")
			(hatch none 0.5)
			(connect_pads
				(clearance 0)
			)
			(min_thickness 0.25)
			(keepout
				(tracks not_allowed)
				(vias allowed)
				(pads allowed)
				(copperpour not_allowed)
				(footprints allowed)
			)
			(placement
				(enabled no)
				(sheetname "")
			)
			(fill
				(thermal_gap 0.5)
				(thermal_bridge_width 0.5)
				(island_removal_mode 0)
			)
			(polygon
				(pts
					(xy 340.416134 4.915154) (xy 340.416134 5.010658) (xy 339.819234 5.010658) (xy 339.819234 5.417058)
					(xy 340.416134 5.417058) (xy 340.416134 5.51053) (xy 339.819234 5.51053) (xy 339.819234 5.91693)
					(xy 340.416134 5.91693) (xy 340.416134 6.012434) (xy 339.717634 6.012434) (xy 339.717634 4.915154)
				)
			)
		)
		(zone
			(layers "F.Cu" "B.Cu" "In1.Cu" "In2.Cu" "In3.Cu" "In4.Cu" "In5.Cu" "In6.Cu"
				"In7.Cu" "In8.Cu" "In9.Cu" "In10.Cu" "In11.Cu" "In12.Cu" "In13.Cu" "In14.Cu"
				"In15.Cu" "In16.Cu"
			)
			(hatch none 0.5)
			(connect_pads
				(clearance 0)
			)
			(min_thickness 0.25)
			(keepout
				(tracks not_allowed)
				(vias allowed)
				(pads allowed)
				(copperpour not_allowed)
				(footprints allowed)
			)
			(placement
				(enabled no)
				(sheetname "")
			)
			(fill
				(thermal_gap 0.5)
				(thermal_bridge_width 0.5)
				(island_removal_mode 0)
			)
			(polygon
				(pts
					(arc
						(start 337.342734 4.193794)
						(mid 335.488534 4.193794)
						(end 337.342734 4.193794)
					)
				)
			)
		)
		(zone
			(layers "F.Cu" "B.Cu" "In1.Cu" "In2.Cu" "In3.Cu" "In4.Cu" "In5.Cu" "In6.Cu"
				"In7.Cu" "In8.Cu" "In9.Cu" "In10.Cu" "In11.Cu" "In12.Cu" "In13.Cu" "In14.Cu"
				"In15.Cu" "In16.Cu"
			)
			(hatch none 0.5)
			(connect_pads
				(clearance 0)
			)
			(min_thickness 0.25)
			(keepout
				(tracks not_allowed)
				(vias allowed)
				(pads allowed)
				(copperpour not_allowed)
				(footprints allowed)
			)
			(placement
				(enabled no)
				(sheetname "")
			)
			(fill
				(thermal_gap 0.5)
				(thermal_bridge_width 0.5)
				(island_removal_mode 0)
			)
			(polygon
				(pts
					(arc
						(start 337.342734 6.733794)
						(mid 335.488534 6.733794)
						(end 337.342734 6.733794)
					)
				)
			)
		)
		(zone
			(layers "F.Cu" "B.Cu" "In1.Cu" "In2.Cu" "In3.Cu" "In4.Cu" "In5.Cu" "In6.Cu"
				"In7.Cu" "In8.Cu" "In9.Cu" "In10.Cu" "In11.Cu" "In12.Cu" "In13.Cu" "In14.Cu"
				"In15.Cu" "In16.Cu"
			)
			(hatch none 0.5)
			(connect_pads
				(clearance 0)
			)
			(min_thickness 0.25)
			(keepout
				(tracks not_allowed)
				(vias allowed)
				(pads allowed)
				(copperpour not_allowed)
				(footprints allowed)
			)
			(placement
				(enabled no)
				(sheetname "")
			)
			(fill
				(thermal_gap 0.5)
				(thermal_bridge_width 0.5)
				(island_removal_mode 0)
			)
			(polygon
				(pts
					(arc
						(start 343.692734 4.193794)
						(mid 341.838534 4.193794)
						(end 343.692734 4.193794)
					)
				)
			)
		)
		(zone
			(layers "F.Cu" "B.Cu" "In1.Cu" "In2.Cu" "In3.Cu" "In4.Cu" "In5.Cu" "In6.Cu"
				"In7.Cu" "In8.Cu" "In9.Cu" "In10.Cu" "In11.Cu" "In12.Cu" "In13.Cu" "In14.Cu"
				"In15.Cu" "In16.Cu"
			)
			(hatch none 0.5)
			(connect_pads
				(clearance 0)
			)
			(min_thickness 0.25)
			(keepout
				(tracks not_allowed)
				(vias allowed)
				(pads allowed)
				(copperpour not_allowed)
				(footprints allowed)
			)
			(placement
				(enabled no)
				(sheetname "")
			)
			(fill
				(thermal_gap 0.5)
				(thermal_bridge_width 0.5)
				(island_removal_mode 0)
			)
			(polygon
				(pts
					(arc
						(start 343.692734 6.733794)
						(mid 341.838534 6.733794)
						(end 343.692734 6.733794)
					)
				)
			)
		)
	)
	(footprint ""
		(layer "F.Cu")
		(at 320.185288 -402.371052 -90)
		(property "Reference" "C1569"
			(at 0 0 270)
			(layer "F.SilkS")
			(hide yes)
			(effects
				(font
					(size 1.27 1.27)
				)
			)
		)
		(property "Value" ""
			(at 0 0 270)
			(layer "F.Fab")
			(effects
				(font
					(size 1.27 1.27)
				)
			)
		)
		(duplicate_pad_numbers_are_jumpers no)
		(fp_line
			(start -0.299974 0.150114)
			(end -0.299974 -0.150114)
			(stroke
				(width 0.1)
				(type default)
			)
			(layer "F.Fab")
		)
		(fp_line
			(start 0.299974 0.150114)
			(end -0.299974 0.150114)
			(stroke
				(width 0.1)
				(type default)
			)
			(layer "F.Fab")
		)
		(fp_line
			(start -0.299974 -0.150114)
			(end 0.299974 -0.150114)
			(stroke
				(width 0.1)
				(type default)
			)
			(layer "F.Fab")
		)
		(fp_line
			(start 0.299974 -0.150114)
			(end 0.299974 0.150114)
			(stroke
				(width 0.1)
				(type default)
			)
			(layer "F.Fab")
		)
		(pad "1" smd rect
			(at -0.2667 0 270)
			(size 0.3048 0.381)
			(layers "F.Cu" "F.Mask" "F.Paste")
			(net "P5E_CPU0_PE4_TX_C_DP<5>")
		)
		(pad "2" smd rect
			(at 0.2667 0 270)
			(size 0.3048 0.381)
			(layers "F.Cu" "F.Mask" "F.Paste")
			(net "P5E_CPU0_PE4_TX_DP<5>")
		)
	)
)
